# T6G (Grand Teton) — schematic netlist excerpt (pin names and nets, part order shuffled) for the footprints in the layout excerpt that follows; sources: Cadence DE-HDL packaged netlist, KiCad conversion of 04192023_DAF0TMB3IC0_F0TG_MB_C_brd_V02_OCP.brd

PR6555  Q_RES  1.5 1% EMPTY  pkg 0402LF  page 363 : A = SW_P0V9_RETIMER_CPU0_SW1_RC ; B = GND

X8007  TP_TDR_4P_FTS  TP_TDR_4P_DIP EMPTY  pkg TH  page 260
  S1  = TDR_DIFF_85_TOP_DN
  P1  = T1_GND
  P2  = T1_GND
  S2  = TDR_DIFF_85_TOP_DP

(kicad_pcb
	(version 20260206)
	(generator "pcbnew")
	(generator_version "10.0")
	(general
		(thickness 1.6)
		(legacy_teardrops no)
	)
	(paper "A4")
	(title_block
		(title "04192023_DAF0TMB3IC0_F0TG_MB_C_brd_V02_OCP.brd")
		(comment 1 "Grand Teton / footprints 1809-1810 of 8354")
	)
	(layers
		(0 "F.Cu" signal "TOP")
		(4 "In1.Cu" signal "GND")
		(6 "In2.Cu" signal "IN1")
		(8 "In3.Cu" signal "GND1")
		(10 "In4.Cu" signal "IN2")
		(12 "In5.Cu" signal "GND2")
		(14 "In6.Cu" signal "IN3")
		(16 "In7.Cu" signal "GND3")
		(18 "In8.Cu" signal "VCC")
		(20 "In9.Cu" signal "VCC1")
		(22 "In10.Cu" signal "GND4")
		(24 "In11.Cu" signal "IN4")
		(26 "In12.Cu" signal "GND5")
		(28 "In13.Cu" signal "IN5")
		(30 "In14.Cu" signal "GND6")
		(32 "In15.Cu" signal "IN6")
		(34 "In16.Cu" signal "GND7")
		(2 "B.Cu" signal "BOTTOM")
		(9 "F.Adhes" user "F.Adhesive")
		(11 "B.Adhes" user "B.Adhesive")
		(13 "F.Paste" user "Package Geometry/Pastemask Top")
		(15 "B.Paste" user "Package Geometry/Pastemask Bottom")
		(5 "F.SilkS" user "Ref Des/Silkscreen Top")
		(7 "B.SilkS" user "Ref Des/Silkscreen Bottom")
		(1 "F.Mask" user "Board Geometry/Soldermask Top")
		(3 "B.Mask" user "Board Geometry/Soldermask Bottom")
		(17 "Dwgs.User" user "User.Drawings")
		(19 "Cmts.User" user "User.Comments")
		(21 "Eco1.User" user "User.Eco1")
		(23 "Eco2.User" user "User.Eco2")
		(25 "Edge.Cuts" user "Board Geometry/Outline")
		(27 "Margin" user)
		(31 "F.CrtYd" user "Package Geometry/Place Bound Top")
		(29 "B.CrtYd" user "Package Geometry/Place Bound Bottom")
		(35 "F.Fab" user "Ref Des/Assembly Top")
		(33 "B.Fab" user "Ref Des/Assembly Bottom")
	)
	(footprint ""
		(layer "F.Cu")
		(at 440.93003 -395.699234 90)
		(property "Reference" "PR6555"
			(at 0 0 90)
			(layer "F.SilkS")
			(hide yes)
			(effects
				(font
					(size 1.27 1.27)
				)
			)
		)
		(property "Value" ""
			(at 0 0 90)
			(layer "F.Fab")
			(effects
				(font
					(size 1.27 1.27)
				)
			)
		)
		(duplicate_pad_numbers_are_jumpers no)
		(fp_line
			(start 0.7874 -0.4064)
			(end 0.7874 0.4064)
			(stroke
				(width 0.1524)
				(type default)
			)
			(layer "F.SilkS")
		)
		(fp_line
			(start -0.7874 -0.4064)
			(end 0.7874 -0.4064)
			(stroke
				(width 0.1524)
				(type default)
			)
			(layer "F.SilkS")
		)
		(fp_line
			(start 0.7874 0.4064)
			(end -0.7874 0.4064)
			(stroke
				(width 0.1524)
				(type default)
			)
			(layer "F.SilkS")
		)
		(fp_line
			(start -0.7874 0.4064)
			(end -0.7874 -0.4064)
			(stroke
				(width 0.1524)
				(type default)
			)
			(layer "F.SilkS")
		)
		(fp_line
			(start -0.12065 -0.305054)
			(end -0.12065 -0.2794)
			(stroke
				(width 0.1)
				(type default)
			)
			(layer "F.Fab")
		)
		(fp_line
			(start -0.67945 -0.305054)
			(end -0.12065 -0.305054)
			(stroke
				(width 0.1)
				(type default)
			)
			(layer "F.Fab")
		)
		(fp_line
			(start 0.67945 -0.3048)
			(end 0.67945 0.3048)
			(stroke
				(width 0.1)
				(type default)
			)
			(layer "F.Fab")
		)
		(fp_line
			(start 0.12065 -0.3048)
			(end 0.67945 -0.3048)
			(stroke
				(width 0.1)
				(type default)
			)
			(layer "F.Fab")
		)
		(fp_line
			(start 0.12065 -0.2794)
			(end 0.12065 -0.3048)
			(stroke
				(width 0.1)
				(type default)
			)
			(layer "F.Fab")
		)
		(fp_line
			(start -0.12065 -0.2794)
			(end 0.12065 -0.2794)
			(stroke
				(width 0.1)
				(type default)
			)
			(layer "F.Fab")
		)
		(fp_line
			(start 0.120396 0.2794)
			(end -0.12065 0.2794)
			(stroke
				(width 0.1)
				(type default)
			)
			(layer "F.Fab")
		)
		(fp_line
			(start -0.12065 0.2794)
			(end -0.12065 0.3048)
			(stroke
				(width 0.1)
				(type default)
			)
			(layer "F.Fab")
		)
		(fp_line
			(start 0.67945 0.3048)
			(end 0.120396 0.3048)
			(stroke
				(width 0.1)
				(type default)
			)
			(layer "F.Fab")
		)
		(fp_line
			(start 0.120396 0.3048)
			(end 0.120396 0.2794)
			(stroke
				(width 0.1)
				(type default)
			)
			(layer "F.Fab")
		)
		(fp_line
			(start -0.12065 0.3048)
			(end -0.67945 0.3048)
			(stroke
				(width 0.1)
				(type default)
			)
			(layer "F.Fab")
		)
		(fp_line
			(start -0.67945 0.3048)
			(end -0.67945 -0.305054)
			(stroke
				(width 0.1)
				(type default)
			)
			(layer "F.Fab")
		)
		(pad "1" smd circle
			(at -0.40005 0 90)
			(size 0 0)
			(layers "F.Cu" "F.Mask" "F.Paste")
			(net "SW_P0V9_RETIMER_CPU0_SW1_RC")
		)
		(pad "2" smd circle
			(at 0.40005 0 90)
			(size 0 0)
			(layers "F.Cu" "F.Mask" "F.Paste")
			(net "GND")
		)
	)
	(footprint ""
		(layer "F.Cu")
		(at 520.044426 -142.882874 90)
		(property "Reference" "X8007"
			(at -2.028444 2.042922 0)
			(unlocked yes)
			(layer "F.SilkS")
			(effects
				(font
					(size 0.7874 0.5842)
					(thickness 0.1524)
				)
				(justify left)
			)
		)
		(property "Value" ""
			(at 0 0 90)
			(layer "F.Fab")
			(effects
				(font
					(size 1.27 1.27)
				)
			)
		)
		(property "Device Type" "TP_TDR_4P_FTS_TH-TP_TDR_4P_DIP,EMPTY,TP15"
			(at 1.30175 1.27 180)
			(unlocked yes)
			(layer "F.Fab")
			(hide yes)
			(effects
				(font
					(size 0.635 0.4064)
					(thickness 0.1524)
				)
			)
		)
		(property "User Part Number" "N_A"
			(at 1.30175 1.27 180)
			(unlocked yes)
			(layer "Cmts.User")
			(hide yes)
			(effects
				(font
					(size 0.635 0.4064)
					(thickness 0.1524)
				)
			)
		)
		(duplicate_pad_numbers_are_jumpers no)
		(fp_line
			(start 2.54 -1.27)
			(end 0 -1.27)
			(stroke
				(width 0.1524)
				(type default)
			)
			(layer "F.SilkS")
		)
		(fp_line
			(start 0 -1.27)
			(end 0 -0.635)
			(stroke
				(width 0.1524)
				(type default)
			)
			(layer "F.SilkS")
		)
		(fp_line
			(start 2.54 -1.1303)
			(end 2.54 -1.27)
			(stroke
				(width 0.1524)
				(type default)
			)
			(layer "F.SilkS")
		)
		(fp_line
			(start 0 0.635)
			(end 0 1.905)
			(stroke
				(width 0.1524)
				(type default)
			)
			(layer "F.SilkS")
		)
		(fp_line
			(start 2.54 1.4097)
			(end 2.54 1.1303)
			(stroke
				(width 0.1524)
				(type default)
			)
			(layer "F.SilkS")
		)
		(fp_line
			(start 0 3.175)
			(end 0 3.81)
			(stroke
				(width 0.1524)
				(type default)
			)
			(layer "F.SilkS")
		)
		(fp_line
			(start 2.54 3.81)
			(end 2.54 3.6703)
			(stroke
				(width 0.1524)
				(type default)
			)
			(layer "F.SilkS")
		)
		(fp_line
			(start 0 3.81)
			(end 2.54 3.81)
			(stroke
				(width 0.1524)
				(type default)
			)
			(layer "F.SilkS")
		)
		(fp_poly
			(pts
				(xy -2.285746 -0.762) (xy -0.761746 0) (xy -2.285746 0.762)
			)
			(stroke
				(width 0)
				(type default)
			)
			(fill yes)
			(layer "F.SilkS")
		)
		(fp_line
			(start 2.54 -1.27)
			(end 0 -1.27)
			(stroke
				(width 0.1)
				(type default)
			)
			(layer "F.Fab")
		)
		(fp_line
			(start 0 -1.27)
			(end 0 3.81)
			(stroke
				(width 0.1)
				(type default)
			)
			(layer "F.Fab")
		)
		(fp_line
			(start 2.54 3.81)
			(end 2.54 -1.27)
			(stroke
				(width 0.1)
				(type default)
			)
			(layer "F.Fab")
		)
		(fp_line
			(start 0 3.81)
			(end 2.54 3.81)
			(stroke
				(width 0.1)
				(type default)
			)
			(layer "F.Fab")
		)
		(fp_poly
			(pts
				(xy -0.761746 0) (xy -2.285746 -0.762) (xy -2.285746 0.762)
			)
			(stroke
				(width 0)
				(type default)
			)
			(fill yes)
			(layer "F.Fab")
		)
		(pad "1" thru_hole circle
			(at 0 0 90)
			(size 1.0033 1.0033)
			(drill 0.249936)
			(layers "*.Cu" "*.Mask")
			(remove_unused_layers no)
			(net "TDR_DIFF_85_TOP_DN")
			(clearance 0.10795)
			(thermal_gap 0.10795)
			(padstack
				(mode front_inner_back)
				(layer "Inner"
					(shape circle)
					(size 0.8001 0.8001)
					(clearance 0.1524)
				)
				(layer "B.Cu"
					(shape circle)
					(size 1.0033 1.0033)
					(clearance 0.10795)
				)
			)
		)
		(pad "2" thru_hole circle
			(at 2.54 0 90)
			(size 1.9939 1.9939)
			(drill 0.249936)
			(layers "*.Cu" "*.Mask")
			(remove_unused_layers no)
			(net "T1_GND")
			(clearance 0.10795)
			(thermal_gap 0.10795)
			(padstack
				(mode front_inner_back)
				(layer "Inner"
					(shape circle)
					(size 0.8001 0.8001)
					(clearance 0.1524)
				)
				(layer "B.Cu"
					(shape circle)
					(size 1.9939 1.9939)
					(clearance 0.10795)
				)
			)
		)
		(pad "3" thru_hole circle
			(at 2.54 2.54 90)
			(size 1.9939 1.9939)
			(drill 0.249936)
			(layers "*.Cu" "*.Mask")
			(remove_unused_layers no)
			(net "T1_GND")
			(clearance 0.10795)
			(thermal_gap 0.10795)
			(padstack
				(mode front_inner_back)
				(layer "Inner"
					(shape circle)
					(size 0.8001 0.8001)
					(clearance 0.1524)
				)
				(layer "B.Cu"
					(shape circle)
					(size 1.9939 1.9939)
					(clearance 0.10795)
				)
			)
		)
		(pad "4" thru_hole circle
			(at 0 2.54 90)
			(size 1.0033 1.0033)
			(drill 0.249936)
			(layers "*.Cu" "*.Mask")
			(remove_unused_layers no)
			(net "TDR_DIFF_85_TOP_DP")
			(clearance 0.10795)
			(thermal_gap 0.10795)
			(padstack
				(mode front_inner_back)
				(layer "Inner"
					(shape circle)
					(size 0.8001 0.8001)
					(clearance 0.1524)
				)
				(layer "B.Cu"
					(shape circle)
					(size 1.0033 1.0033)
					(clearance 0.10795)
				)
			)
		)
	)
)
